(kicad_pcb
	(version 20260206)
	(generator "pcbnew")
	(generator_version "10.0")
	(general
		(thickness 1.6)
		(legacy_teardrops no)
	)
	(paper "A4")
	(title_block
		(title "Wiwynn_Tioga_Pass_MB.brd")
		(comment 1 "Tioga Pass / footprints 2755-2761 of 4770")
	)
	(layers
		(0 "F.Cu" signal "TOP")
		(4 "In1.Cu" signal "L2GND")
		(6 "In2.Cu" signal "L3")
		(8 "In3.Cu" signal "L4GND")
		(10 "In4.Cu" signal "L5")
		(12 "In5.Cu" signal "L6GND")
		(14 "In6.Cu" signal "L7VCC")
		(16 "In7.Cu" signal "L8VCC")
		(18 "In8.Cu" signal "L9GND")
		(20 "In9.Cu" signal "L10")
		(22 "In10.Cu" signal "L11GND")
		(24 "In11.Cu" signal "L12")
		(26 "In12.Cu" signal "L13GND")
		(2 "B.Cu" signal "BOTTOM")
		(9 "F.Adhes" user "F.Adhesive")
		(11 "B.Adhes" user "B.Adhesive")
		(13 "F.Paste" user "Package Geometry/Pastemask Top")
		(15 "B.Paste" user "Package Geometry/Pastemask Bottom")
		(5 "F.SilkS" user "Ref Des/Silkscreen Top")
		(7 "B.SilkS" user "Ref Des/Silkscreen Bottom")
		(1 "F.Mask" user "Board Geometry/Soldermask Top")
		(3 "B.Mask" user "Board Geometry/Soldermask Bottom")
		(17 "Dwgs.User" user "User.Drawings")
		(19 "Cmts.User" user "User.Comments")
		(21 "Eco1.User" user "User.Eco1")
		(23 "Eco2.User" user "User.Eco2")
		(25 "Edge.Cuts" user "Board Geometry/Outline")
		(27 "Margin" user)
		(31 "F.CrtYd" user "Package Geometry/Place Bound Top")
		(29 "B.CrtYd" user "Package Geometry/Place Bound Bottom")
		(35 "F.Fab" user "Ref Des/Assembly Top")
		(33 "B.Fab" user "Ref Des/Assembly Bottom")
	)
	(footprint ""
		(layer "B.Cu")
		(at 370.000276 -156.15158 180)
		(property "Reference" "C22W23"
			(at 0 0 0)
			(layer "B.SilkS")
			(hide yes)
			(effects
				(font
					(size 1.27 1.27)
				)
				(justify mirror)
			)
		)
		(property "Value" "*"
			(at 0.0762 -6.2357 180)
			(unlocked yes)
			(layer "B.Fab")
			(hide yes)
			(effects
				(font
					(size 1.27 1.016)
					(thickness 0.1524)
				)
				(justify mirror)
			)
		)
		(property "Device Type" "SC22U16V5MX-4-GP_SMD-BCG5-SC22A"
			(at 0.0762 -8.2677 180)
			(unlocked yes)
			(layer "B.Fab")
			(hide yes)
			(effects
				(font
					(size 1.27 1.016)
					(thickness 0.1524)
				)
				(justify mirror)
			)
		)
		(duplicate_pad_numbers_are_jumpers no)
		(fp_line
			(start -0.635 0)
			(end 0.635 0)
			(stroke
				(width 0.508)
				(type default)
			)
			(layer "B.SilkS")
		)
		(fp_rect
			(start 0.9652 1.778)
			(end -0.9652 -1.778)
			(stroke
				(width 0)
				(type default)
			)
			(fill no)
			(layer "B.CrtYd")
		)
		(fp_poly
			(pts
				(xy 0.9652 -1.778) (xy -0.9652 -1.778) (xy -0.9652 1.778) (xy 0.9652 1.778)
			)
			(stroke
				(width 0)
				(type default)
			)
			(fill no)
			(layer "B.Fab")
		)
		(pad "1" smd rect
			(at 0 -0.9652)
			(size 1.397 1.143)
			(layers "B.Cu" "B.Mask" "B.Paste")
			(net "VR_FET_SW_P12V_STBY_PVDDQ_DEF")
		)
		(pad "2" smd rect
			(at 0 0.9652)
			(size 1.397 1.143)
			(layers "B.Cu" "B.Mask" "B.Paste")
			(net "GND")
		)
	)
	(footprint ""
		(layer "B.Cu")
		(at 354.301806 -60.368434)
		(property "Reference" "R2U29"
			(at 0 0 0)
			(layer "B.SilkS")
			(hide yes)
			(effects
				(font
					(size 1.27 1.27)
				)
				(justify mirror)
			)
		)
		(property "Value" ""
			(at 0 0 0)
			(layer "B.Fab")
			(effects
				(font
					(size 1.27 1.27)
				)
				(justify mirror)
			)
		)
		(duplicate_pad_numbers_are_jumpers no)
		(fp_poly
			(pts
				(xy 0.2794 -0.1016) (xy -0.2794 -0.1016) (xy -0.2794 0.9906) (xy 0.2794 0.9906)
			)
			(stroke
				(width 0)
				(type default)
			)
			(fill no)
			(layer "B.CrtYd")
		)
		(fp_line
			(start -0.2794 -0.1016)
			(end 0.2794 -0.1016)
			(stroke
				(width 0.1)
				(type default)
			)
			(layer "B.Fab")
		)
		(fp_line
			(start -0.2794 0.9906)
			(end -0.2794 -0.1016)
			(stroke
				(width 0.1)
				(type default)
			)
			(layer "B.Fab")
		)
		(fp_line
			(start 0.2794 -0.1016)
			(end 0.2794 0.9906)
			(stroke
				(width 0.1)
				(type default)
			)
			(layer "B.Fab")
		)
		(fp_line
			(start 0.2794 0.9906)
			(end -0.2794 0.9906)
			(stroke
				(width 0.1)
				(type default)
			)
			(layer "B.Fab")
		)
		(pad "1" smd rect
			(at 0 0 180)
			(size 0.508 0.508)
			(layers "B.Cu" "B.Mask" "B.Paste")
			(net "P3E_CPU0_PE1_SS_RXN<7>")
		)
		(pad "2" smd rect
			(at 0 0.889 180)
			(size 0.508 0.508)
			(layers "B.Cu" "B.Mask" "B.Paste")
			(net "P3E_CPU0_PE1_SS_R_RXN<7>")
		)
		(zone
			(layer "B.Cu")
			(hatch none 0.5)
			(connect_pads
				(clearance 0)
			)
			(min_thickness 0.25)
			(keepout
				(tracks allowed)
				(vias not_allowed)
				(pads allowed)
				(copperpour not_allowed)
				(footprints allowed)
			)
			(placement
				(enabled no)
				(sheetname "")
			)
			(fill
				(thermal_gap 0.5)
				(thermal_bridge_width 0.5)
				(island_removal_mode 0)
			)
			(polygon
				(pts
					(xy 354.555806 -60.114434) (xy 354.047806 -60.114434) (xy 354.047806 -59.733434) (xy 354.555806 -59.733434)
				)
			)
		)
		(zone
			(layer "B.Cu")
			(hatch none 0.5)
			(connect_pads
				(clearance 0)
			)
			(min_thickness 0.25)
			(keepout
				(tracks not_allowed)
				(vias allowed)
				(pads allowed)
				(copperpour not_allowed)
				(footprints allowed)
			)
			(placement
				(enabled no)
				(sheetname "")
			)
			(fill
				(thermal_gap 0.5)
				(thermal_bridge_width 0.5)
				(island_removal_mode 0)
			)
			(polygon
				(pts
					(xy 354.555806 -59.733434) (xy 354.047806 -59.733434) (xy 354.047806 -60.114434) (xy 354.555806 -60.114434)
				)
			)
		)
	)
	(footprint ""
		(layer "B.Cu")
		(at 117.1956 -73.406 -90)
		(property "Reference" "R7P16"
			(at 0 0 90)
			(layer "B.SilkS")
			(hide yes)
			(effects
				(font
					(size 1.27 1.27)
				)
				(justify mirror)
			)
		)
		(property "Value" ""
			(at 0 0 90)
			(layer "B.Fab")
			(effects
				(font
					(size 1.27 1.27)
				)
				(justify mirror)
			)
		)
		(duplicate_pad_numbers_are_jumpers no)
		(fp_poly
			(pts
				(xy 0.2794 -0.1016) (xy -0.2794 -0.1016) (xy -0.2794 0.9906) (xy 0.2794 0.9906)
			)
			(stroke
				(width 0)
				(type default)
			)
			(fill no)
			(layer "B.CrtYd")
		)
		(fp_line
			(start -0.2794 0.9906)
			(end -0.2794 -0.1016)
			(stroke
				(width 0.1)
				(type default)
			)
			(layer "B.Fab")
		)
		(fp_line
			(start 0.2794 0.9906)
			(end -0.2794 0.9906)
			(stroke
				(width 0.1)
				(type default)
			)
			(layer "B.Fab")
		)
		(fp_line
			(start -0.2794 -0.1016)
			(end 0.2794 -0.1016)
			(stroke
				(width 0.1)
				(type default)
			)
			(layer "B.Fab")
		)
		(fp_line
			(start 0.2794 -0.1016)
			(end 0.2794 0.9906)
			(stroke
				(width 0.1)
				(type default)
			)
			(layer "B.Fab")
		)
		(pad "1" smd rect
			(at 0 0 90)
			(size 0.508 0.508)
			(layers "B.Cu" "B.Mask" "B.Paste")
			(net "A_CPU1_GHJ_RCOMP0")
		)
		(pad "2" smd rect
			(at 0 0.889 90)
			(size 0.508 0.508)
			(layers "B.Cu" "B.Mask" "B.Paste")
			(net "GND")
		)
		(zone
			(layer "B.Cu")
			(hatch none 0.5)
			(connect_pads
				(clearance 0)
			)
			(min_thickness 0.25)
			(keepout
				(tracks not_allowed)
				(vias allowed)
				(pads allowed)
				(copperpour not_allowed)
				(footprints allowed)
			)
			(placement
				(enabled no)
				(sheetname "")
			)
			(fill
				(thermal_gap 0.5)
				(thermal_bridge_width 0.5)
				(island_removal_mode 0)
			)
			(polygon
				(pts
					(xy 116.5606 -73.152) (xy 116.5606 -73.66) (xy 116.9416 -73.66) (xy 116.9416 -73.152)
				)
			)
		)
		(zone
			(layer "B.Cu")
			(hatch none 0.5)
			(connect_pads
				(clearance 0)
			)
			(min_thickness 0.25)
			(keepout
				(tracks allowed)
				(vias not_allowed)
				(pads allowed)
				(copperpour not_allowed)
				(footprints allowed)
			)
			(placement
				(enabled no)
				(sheetname "")
			)
			(fill
				(thermal_gap 0.5)
				(thermal_bridge_width 0.5)
				(island_removal_mode 0)
			)
			(polygon
				(pts
					(xy 116.9416 -73.152) (xy 116.9416 -73.66) (xy 116.5606 -73.66) (xy 116.5606 -73.152)
				)
			)
		)
	)
	(footprint ""
		(layer "B.Cu")
		(at 375.408952 -43.224958)
		(property "Reference" "R2T32"
			(at 0 0 0)
			(layer "B.SilkS")
			(hide yes)
			(effects
				(font
					(size 1.27 1.27)
				)
				(justify mirror)
			)
		)
		(property "Value" ""
			(at 0 0 0)
			(layer "B.Fab")
			(effects
				(font
					(size 1.27 1.27)
				)
				(justify mirror)
			)
		)
		(duplicate_pad_numbers_are_jumpers no)
		(fp_poly
			(pts
				(xy 0.2794 -0.1016) (xy -0.2794 -0.1016) (xy -0.2794 0.9906) (xy 0.2794 0.9906)
			)
			(stroke
				(width 0)
				(type default)
			)
			(fill no)
			(layer "B.CrtYd")
		)
		(fp_line
			(start -0.2794 -0.1016)
			(end 0.2794 -0.1016)
			(stroke
				(width 0.1)
				(type default)
			)
			(layer "B.Fab")
		)
		(fp_line
			(start -0.2794 0.9906)
			(end -0.2794 -0.1016)
			(stroke
				(width 0.1)
				(type default)
			)
			(layer "B.Fab")
		)
		(fp_line
			(start 0.2794 -0.1016)
			(end 0.2794 0.9906)
			(stroke
				(width 0.1)
				(type default)
			)
			(layer "B.Fab")
		)
		(fp_line
			(start 0.2794 0.9906)
			(end -0.2794 0.9906)
			(stroke
				(width 0.1)
				(type default)
			)
			(layer "B.Fab")
		)
		(pad "1" smd rect
			(at 0 0 180)
			(size 0.508 0.508)
			(layers "B.Cu" "B.Mask" "B.Paste")
			(net "H_CPU0_ERR1_G_N")
		)
		(pad "2" smd rect
			(at 0 0.889 180)
			(size 0.508 0.508)
			(layers "B.Cu" "B.Mask" "B.Paste")
			(net "H_CPU_ERR1_GTL_R_N")
		)
		(zone
			(layer "B.Cu")
			(hatch none 0.5)
			(connect_pads
				(clearance 0)
			)
			(min_thickness 0.25)
			(keepout
				(tracks allowed)
				(vias not_allowed)
				(pads allowed)
				(copperpour not_allowed)
				(footprints allowed)
			)
			(placement
				(enabled no)
				(sheetname "")
			)
			(fill
				(thermal_gap 0.5)
				(thermal_bridge_width 0.5)
				(island_removal_mode 0)
			)
			(polygon
				(pts
					(xy 375.662952 -42.970958) (xy 375.154952 -42.970958) (xy 375.154952 -42.589958) (xy 375.662952 -42.589958)
				)
			)
		)
		(zone
			(layer "B.Cu")
			(hatch none 0.5)
			(connect_pads
				(clearance 0)
			)
			(min_thickness 0.25)
			(keepout
				(tracks not_allowed)
				(vias allowed)
				(pads allowed)
				(copperpour not_allowed)
				(footprints allowed)
			)
			(placement
				(enabled no)
				(sheetname "")
			)
			(fill
				(thermal_gap 0.5)
				(thermal_bridge_width 0.5)
				(island_removal_mode 0)
			)
			(polygon
				(pts
					(xy 375.662952 -42.589958) (xy 375.154952 -42.589958) (xy 375.154952 -42.970958) (xy 375.662952 -42.970958)
				)
			)
		)
	)
	(footprint ""
		(layer "B.Cu")
		(at 371.54485 -72.29348)
		(property "Reference" "C2P4"
			(at 0 0 0)
			(layer "B.SilkS")
			(hide yes)
			(effects
				(font
					(size 1.27 1.27)
				)
				(justify mirror)
			)
		)
		(property "Value" ""
			(at 0 0 0)
			(layer "B.Fab")
			(effects
				(font
					(size 1.27 1.27)
				)
				(justify mirror)
			)
		)
		(duplicate_pad_numbers_are_jumpers no)
		(fp_rect
			(start 0.2794 0.9144)
			(end -0.2794 -0.1143)
			(stroke
				(width 0)
				(type default)
			)
			(fill no)
			(layer "B.CrtYd")
		)
		(fp_line
			(start -0.2794 -0.1143)
			(end -0.2794 0.9144)
			(stroke
				(width 0.1)
				(type default)
			)
			(layer "B.Fab")
		)
		(fp_line
			(start -0.2794 0.9144)
			(end 0.2794 0.9144)
			(stroke
				(width 0.1)
				(type default)
			)
			(layer "B.Fab")
		)
		(fp_line
			(start 0.2794 -0.1143)
			(end -0.2794 -0.1143)
			(stroke
				(width 0.1)
				(type default)
			)
			(layer "B.Fab")
		)
		(fp_line
			(start 0.2794 0.9144)
			(end 0.2794 -0.1143)
			(stroke
				(width 0.1)
				(type default)
			)
			(layer "B.Fab")
		)
		(pad "1" smd custom
			(at 0 0 270)
			(size 0.10414 0.10414)
			(layers "B.Cu" "B.Mask" "B.Paste")
			(net "P3V3_STBY")
			(options
				(clearance outline)
				(anchor circle)
			)
			(primitives
				(gr_poly
					(pts
						(xy -0.20828 -0.08636) (xy -0.20828 0.08636) (xy -0.08636 0.20828) (xy 0.086614 0.20828) (xy 0.20828 0.086614)
						(xy 0.20828 -0.08636) (xy 0.08636 -0.20828) (xy -0.08636 -0.20828)
					)
					(width 0)
					(fill yes)
				)
			)
		)
		(pad "2" smd custom
			(at 0 0.8001 270)
			(size 0.10414 0.10414)
			(layers "B.Cu" "B.Mask" "B.Paste")
			(net "GND")
			(options
				(clearance outline)
				(anchor circle)
			)
			(primitives
				(gr_poly
					(pts
						(xy -0.20828 -0.08636) (xy -0.20828 0.08636) (xy -0.08636 0.20828) (xy 0.086614 0.20828) (xy 0.20828 0.086614)
						(xy 0.20828 -0.08636) (xy 0.08636 -0.20828) (xy -0.08636 -0.20828)
					)
					(width 0)
					(fill yes)
				)
			)
		)
		(zone
			(layer "B.Cu")
			(hatch none 0.5)
			(connect_pads
				(clearance 0)
			)
			(min_thickness 0.25)
			(keepout
				(tracks not_allowed)
				(vias allowed)
				(pads allowed)
				(copperpour not_allowed)
				(footprints allowed)
			)
			(placement
				(enabled no)
				(sheetname "")
			)
			(fill
				(thermal_gap 0.5)
				(thermal_bridge_width 0.5)
				(island_removal_mode 0)
			)
			(polygon
				(pts
					(xy 371.63248 -72.08393) (xy 371.63248 -71.70293) (xy 371.45722 -71.70293) (xy 371.456966 -72.08393)
				)
			)
		)
		(zone
			(layer "B.Cu")
			(hatch none 0.5)
			(connect_pads
				(clearance 0)
			)
			(min_thickness 0.25)
			(keepout
				(tracks allowed)
				(vias not_allowed)
				(pads allowed)
				(copperpour not_allowed)
				(footprints allowed)
			)
			(placement
				(enabled no)
				(sheetname "")
			)
			(fill
				(thermal_gap 0.5)
				(thermal_bridge_width 0.5)
				(island_removal_mode 0)
			)
			(polygon
				(pts
					(xy 371.63248 -72.08393) (xy 371.63248 -71.70293) (xy 371.45722 -71.70293) (xy 371.456966 -72.08393)
				)
			)
		)
	)
	(footprint ""
		(layer "B.Cu")
		(at 418.871654 -36.7665 -90)
		(property "Reference" "C25W52"
			(at 0.8382 -0.67818 270)
			(unlocked yes)
			(layer "B.SilkS")
			(effects
				(font
					(size 0.4064 0.254)
					(thickness 0.1524)
				)
				(justify left mirror)
			)
		)
		(property "Value" ""
			(at 0 0 90)
			(layer "B.Fab")
			(effects
				(font
					(size 1.27 1.27)
				)
				(justify mirror)
			)
		)
		(duplicate_pad_numbers_are_jumpers no)
		(fp_poly
			(pts
				(xy -0.3048 -0.1016) (xy -0.3048 0.9906) (xy 0.3048 0.9906) (xy 0.3048 -0.1016)
			)
			(stroke
				(width 0)
				(type default)
			)
			(fill no)
			(layer "B.CrtYd")
		)
		(fp_line
			(start -0.3048 0.9906)
			(end -0.3048 -0.1016)
			(stroke
				(width 0.1)
				(type default)
			)
			(layer "B.Fab")
		)
		(fp_line
			(start 0.3048 0.9906)
			(end -0.3048 0.9906)
			(stroke
				(width 0.1)
				(type default)
			)
			(layer "B.Fab")
		)
		(fp_line
			(start -0.3048 -0.1016)
			(end 0.3048 -0.1016)
			(stroke
				(width 0.1)
				(type default)
			)
			(layer "B.Fab")
		)
		(fp_line
			(start 0.3048 -0.1016)
			(end 0.3048 0.9906)
			(stroke
				(width 0.1)
				(type default)
			)
			(layer "B.Fab")
		)
		(pad "1" smd rect
			(at 0 0 90)
			(size 0.508 0.508)
			(layers "B.Cu" "B.Mask" "B.Paste")
			(net "P1V2_AUX_BMC")
		)
		(pad "2" smd rect
			(at 0 0.889 90)
			(size 0.508 0.508)
			(layers "B.Cu" "B.Mask" "B.Paste")
			(net "GND")
		)
		(zone
			(layer "B.Cu")
			(hatch none 0.5)
			(connect_pads
				(clearance 0)
			)
			(min_thickness 0.25)
			(keepout
				(tracks not_allowed)
				(vias allowed)
				(pads allowed)
				(copperpour not_allowed)
				(footprints allowed)
			)
			(placement
				(enabled no)
				(sheetname "")
			)
			(fill
				(thermal_gap 0.5)
				(thermal_bridge_width 0.5)
				(island_removal_mode 0)
			)
			(polygon
				(pts
					(xy 418.236654 -36.5125) (xy 418.236654 -37.0205) (xy 418.617654 -37.0205) (xy 418.617654 -36.5125)
				)
			)
		)
		(zone
			(layer "B.Cu")
			(hatch none 0.5)
			(connect_pads
				(clearance 0)
			)
			(min_thickness 0.25)
			(keepout
				(tracks allowed)
				(vias not_allowed)
				(pads allowed)
				(copperpour not_allowed)
				(footprints allowed)
			)
			(placement
				(enabled no)
				(sheetname "")
			)
			(fill
				(thermal_gap 0.5)
				(thermal_bridge_width 0.5)
				(island_removal_mode 0)
			)
			(polygon
				(pts
					(xy 418.617654 -36.5125) (xy 418.617654 -37.0205) (xy 418.236654 -37.0205) (xy 418.236654 -36.5125)
				)
			)
		)
	)
	(footprint ""
		(layer "B.Cu")
		(at 448.55638 -33.5915 90)
		(property "Reference" "R25W28"
			(at 0 0 90)
			(layer "B.SilkS")
			(hide yes)
			(effects
				(font
					(size 1.27 1.27)
				)
				(justify mirror)
			)
		)
		(property "Value" "*"
			(at -0.064008 -4.108196 90)
			(unlocked yes)
			(layer "B.Fab")
			(hide yes)
			(effects
				(font
					(size 1.27 1.016)
					(thickness 0.1524)
				)
				(justify mirror)
			)
		)
		(property "Device Type" "120R2F-GP_RCL_GP-120R2F-GP,64.A"
			(at -0.064008 -5.632196 90)
			(unlocked yes)
			(layer "B.Fab")
			(hide yes)
			(effects
				(font
					(size 1.27 1.016)
					(thickness 0.1524)
				)
				(justify mirror)
			)
		)
		(duplicate_pad_numbers_are_jumpers no)
		(fp_line
			(start 0.508 -0.9398)
			(end 0.508 0.9398)
			(stroke
				(width 0.1524)
				(type default)
			)
			(layer "B.SilkS")
		)
		(fp_line
			(start -0.508 -0.9398)
			(end 0.508 -0.9398)
			(stroke
				(width 0.1524)
				(type default)
			)
			(layer "B.SilkS")
		)
		(fp_rect
			(start 0.508 0.9398)
			(end -0.508 -0.9398)
			(stroke
				(width 0)
				(type default)
			)
			(fill no)
			(layer "B.CrtYd")
		)
		(fp_rect
			(start 0.508 0.9398)
			(end -0.508 -0.9398)
			(stroke
				(width 0)
				(type default)
			)
			(fill no)
			(layer "B.Fab")
		)
		(pad "1" smd custom
			(at 0 -0.4445 270)
			(size 0.1397 0.1397)
			(layers "B.Cu" "B.Mask" "B.Paste")
			(net "BMC_M_ODT")
			(options
				(clearance outline)
				(anchor circle)
			)
			(primitives
				(gr_poly
					(pts
						(arc
							(start -0.1778 0.2794)
							(mid -0.249642 0.249642)
							(end -0.2794 0.1778)
						)
						(arc
							(start -0.2794 -0.1778)
							(mid -0.249642 -0.249642)
							(end -0.1778 -0.2794)
						)
						(arc
							(start 0.1778 -0.2794)
							(mid 0.249642 -0.249642)
							(end 0.2794 -0.1778)
						)
						(arc
							(start 0.2794 0.1778)
							(mid 0.249642 0.249642)
							(end 0.1778 0.2794)
						)
					)
					(width 0)
					(fill yes)
				)
			)
		)
		(pad "2" smd custom
			(at 0 0.4445 270)
			(size 0.1397 0.1397)
			(layers "B.Cu" "B.Mask" "B.Paste")
			(net "P1V2_AUX_BMC")
			(options
				(clearance outline)
				(anchor circle)
			)
			(primitives
				(gr_poly
					(pts
						(arc
							(start -0.1778 0.2794)
							(mid -0.249642 0.249642)
							(end -0.2794 0.1778)
						)
						(arc
							(start -0.2794 -0.1778)
							(mid -0.249642 -0.249642)
							(end -0.1778 -0.2794)
						)
						(arc
							(start 0.1778 -0.2794)
							(mid 0.249642 -0.249642)
							(end 0.2794 -0.1778)
						)
						(arc
							(start 0.2794 0.1778)
							(mid 0.249642 0.249642)
							(end 0.1778 0.2794)
						)
					)
					(width 0)
					(fill yes)
				)
			)
		)
	)
)
